# T6G (Grand Teton) — schematic netlist excerpt (pin names and nets, part order shuffled) for the footprints in the layout excerpt that follows; sources: Cadence DE-HDL packaged netlist, KiCad conversion of 04192023_DAF0TMB3IC0_F0TG_MB_C_brd_V02_OCP.brd

PC2182  Q_CAP  220PF 50V 10% X7R  pkg 0402  page 263 : A = HSC_ON ; B = AGND_HSC
C1564  Q_CAP  1UF 25V 10% X6S  pkg C0402  page 187 : A = P1V5_BAT_OUT ; B = GND

(kicad_pcb
	(version 20260206)
	(generator "pcbnew")
	(generator_version "10.0")
	(general
		(thickness 1.6)
		(legacy_teardrops no)
	)
	(paper "A4")
	(title_block
		(title "04192023_DAF0TMB3IC0_F0TG_MB_C_brd_V02_OCP.brd")
		(comment 1 "Grand Teton / footprints 788-789 of 8354")
	)
	(layers
		(0 "F.Cu" signal "TOP")
		(4 "In1.Cu" signal "GND")
		(6 "In2.Cu" signal "IN1")
		(8 "In3.Cu" signal "GND1")
		(10 "In4.Cu" signal "IN2")
		(12 "In5.Cu" signal "GND2")
		(14 "In6.Cu" signal "IN3")
		(16 "In7.Cu" signal "GND3")
		(18 "In8.Cu" signal "VCC")
		(20 "In9.Cu" signal "VCC1")
		(22 "In10.Cu" signal "GND4")
		(24 "In11.Cu" signal "IN4")
		(26 "In12.Cu" signal "GND5")
		(28 "In13.Cu" signal "IN5")
		(30 "In14.Cu" signal "GND6")
		(32 "In15.Cu" signal "IN6")
		(34 "In16.Cu" signal "GND7")
		(2 "B.Cu" signal "BOTTOM")
		(9 "F.Adhes" user "F.Adhesive")
		(11 "B.Adhes" user "B.Adhesive")
		(13 "F.Paste" user "Package Geometry/Pastemask Top")
		(15 "B.Paste" user "Package Geometry/Pastemask Bottom")
		(5 "F.SilkS" user "Ref Des/Silkscreen Top")
		(7 "B.SilkS" user "Ref Des/Silkscreen Bottom")
		(1 "F.Mask" user "Board Geometry/Soldermask Top")
		(3 "B.Mask" user "Board Geometry/Soldermask Bottom")
		(17 "Dwgs.User" user "User.Drawings")
		(19 "Cmts.User" user "User.Comments")
		(21 "Eco1.User" user "User.Eco1")
		(23 "Eco2.User" user "User.Eco2")
		(25 "Edge.Cuts" user "Board Geometry/Outline")
		(27 "Margin" user)
		(31 "F.CrtYd" user "Package Geometry/Place Bound Top")
		(29 "B.CrtYd" user "Package Geometry/Place Bound Bottom")
		(35 "F.Fab" user "Ref Des/Assembly Top")
		(33 "B.Fab" user "Ref Des/Assembly Bottom")
	)
	(footprint ""
		(layer "F.Cu")
		(at 204.7621 -404.020782)
		(property "Reference" "PC2182"
			(at 0 0 0)
			(layer "F.SilkS")
			(hide yes)
			(effects
				(font
					(size 1.27 1.27)
				)
			)
		)
		(property "Value" ""
			(at 0 0 0)
			(layer "F.Fab")
			(effects
				(font
					(size 1.27 1.27)
				)
			)
		)
		(duplicate_pad_numbers_are_jumpers no)
		(fp_line
			(start -0.7874 -0.4064)
			(end 0.7874 -0.4064)
			(stroke
				(width 0.1524)
				(type default)
			)
			(layer "F.SilkS")
		)
		(fp_line
			(start -0.7874 0.4064)
			(end -0.7874 -0.4064)
			(stroke
				(width 0.1524)
				(type default)
			)
			(layer "F.SilkS")
		)
		(fp_line
			(start 0.7874 -0.4064)
			(end 0.7874 0.4064)
			(stroke
				(width 0.1524)
				(type default)
			)
			(layer "F.SilkS")
		)
		(fp_line
			(start 0.7874 0.4064)
			(end -0.7874 0.4064)
			(stroke
				(width 0.1524)
				(type default)
			)
			(layer "F.SilkS")
		)
		(fp_line
			(start -0.67945 -0.305054)
			(end -0.12065 -0.305054)
			(stroke
				(width 0.1)
				(type default)
			)
			(layer "F.Fab")
		)
		(fp_line
			(start -0.67945 0.3048)
			(end -0.67945 -0.305054)
			(stroke
				(width 0.1)
				(type default)
			)
			(layer "F.Fab")
		)
		(fp_line
			(start -0.12065 -0.305054)
			(end -0.12065 -0.2794)
			(stroke
				(width 0.1)
				(type default)
			)
			(layer "F.Fab")
		)
		(fp_line
			(start -0.12065 -0.2794)
			(end 0.12065 -0.2794)
			(stroke
				(width 0.1)
				(type default)
			)
			(layer "F.Fab")
		)
		(fp_line
			(start -0.12065 0.2794)
			(end -0.12065 0.3048)
			(stroke
				(width 0.1)
				(type default)
			)
			(layer "F.Fab")
		)
		(fp_line
			(start -0.12065 0.3048)
			(end -0.67945 0.3048)
			(stroke
				(width 0.1)
				(type default)
			)
			(layer "F.Fab")
		)
		(fp_line
			(start 0.120396 0.2794)
			(end -0.12065 0.2794)
			(stroke
				(width 0.1)
				(type default)
			)
			(layer "F.Fab")
		)
		(fp_line
			(start 0.120396 0.3048)
			(end 0.120396 0.2794)
			(stroke
				(width 0.1)
				(type default)
			)
			(layer "F.Fab")
		)
		(fp_line
			(start 0.12065 -0.3048)
			(end 0.67945 -0.3048)
			(stroke
				(width 0.1)
				(type default)
			)
			(layer "F.Fab")
		)
		(fp_line
			(start 0.12065 -0.2794)
			(end 0.12065 -0.3048)
			(stroke
				(width 0.1)
				(type default)
			)
			(layer "F.Fab")
		)
		(fp_line
			(start 0.67945 -0.3048)
			(end 0.67945 0.3048)
			(stroke
				(width 0.1)
				(type default)
			)
			(layer "F.Fab")
		)
		(fp_line
			(start 0.67945 0.3048)
			(end 0.120396 0.3048)
			(stroke
				(width 0.1)
				(type default)
			)
			(layer "F.Fab")
		)
		(pad "1" smd circle
			(at -0.40005 0)
			(size 0 0)
			(layers "F.Cu" "F.Mask" "F.Paste")
			(net "HSC_ON")
		)
		(pad "2" smd circle
			(at 0.40005 0)
			(size 0 0)
			(layers "F.Cu" "F.Mask" "F.Paste")
			(net "AGND_HSC")
		)
	)
	(footprint ""
		(layer "F.Cu")
		(at 296.215562 -19.247358 -90)
		(property "Reference" "C1564"
			(at 0 0 270)
			(layer "F.SilkS")
			(hide yes)
			(effects
				(font
					(size 1.27 1.27)
				)
			)
		)
		(property "Value" ""
			(at 0 0 270)
			(layer "F.Fab")
			(effects
				(font
					(size 1.27 1.27)
				)
			)
		)
		(duplicate_pad_numbers_are_jumpers no)
		(fp_line
			(start -0.7874 0.4064)
			(end -0.7874 -0.4064)
			(stroke
				(width 0.1524)
				(type default)
			)
			(layer "F.SilkS")
		)
		(fp_line
			(start 0.7874 0.4064)
			(end -0.7874 0.4064)
			(stroke
				(width 0.1524)
				(type default)
			)
			(layer "F.SilkS")
		)
		(fp_line
			(start -0.7874 -0.4064)
			(end 0.7874 -0.4064)
			(stroke
				(width 0.1524)
				(type default)
			)
			(layer "F.SilkS")
		)
		(fp_line
			(start 0.7874 -0.4064)
			(end 0.7874 0.4064)
			(stroke
				(width 0.1524)
				(type default)
			)
			(layer "F.SilkS")
		)
		(fp_line
			(start -0.67945 0.3048)
			(end -0.67945 -0.305054)
			(stroke
				(width 0.1)
				(type default)
			)
			(layer "F.Fab")
		)
		(fp_line
			(start -0.12065 0.3048)
			(end -0.67945 0.3048)
			(stroke
				(width 0.1)
				(type default)
			)
			(layer "F.Fab")
		)
		(fp_line
			(start 0.120396 0.3048)
			(end 0.120396 0.2794)
			(stroke
				(width 0.1)
				(type default)
			)
			(layer "F.Fab")
		)
		(fp_line
			(start 0.67945 0.3048)
			(end 0.120396 0.3048)
			(stroke
				(width 0.1)
				(type default)
			)
			(layer "F.Fab")
		)
		(fp_line
			(start -0.12065 0.2794)
			(end -0.12065 0.3048)
			(stroke
				(width 0.1)
				(type default)
			)
			(layer "F.Fab")
		)
		(fp_line
			(start 0.120396 0.2794)
			(end -0.12065 0.2794)
			(stroke
				(width 0.1)
				(type default)
			)
			(layer "F.Fab")
		)
		(fp_line
			(start -0.12065 -0.2794)
			(end 0.12065 -0.2794)
			(stroke
				(width 0.1)
				(type default)
			)
			(layer "F.Fab")
		)
		(fp_line
			(start 0.12065 -0.2794)
			(end 0.12065 -0.3048)
			(stroke
				(width 0.1)
				(type default)
			)
			(layer "F.Fab")
		)
		(fp_line
			(start 0.12065 -0.3048)
			(end 0.67945 -0.3048)
			(stroke
				(width 0.1)
				(type default)
			)
			(layer "F.Fab")
		)
		(fp_line
			(start 0.67945 -0.3048)
			(end 0.67945 0.3048)
			(stroke
				(width 0.1)
				(type default)
			)
			(layer "F.Fab")
		)
		(fp_line
			(start -0.67945 -0.305054)
			(end -0.12065 -0.305054)
			(stroke
				(width 0.1)
				(type default)
			)
			(layer "F.Fab")
		)
		(fp_line
			(start -0.12065 -0.305054)
			(end -0.12065 -0.2794)
			(stroke
				(width 0.1)
				(type default)
			)
			(layer "F.Fab")
		)
		(pad "1" smd circle
			(at -0.40005 0 270)
			(size 0 0)
			(layers "F.Cu" "F.Mask" "F.Paste")
			(net "P1V5_BAT_OUT")
		)
		(pad "2" smd circle
			(at 0.40005 0 270)
			(size 0 0)
			(layers "F.Cu" "F.Mask" "F.Paste")
			(net "GND")
		)
	)
)
